# BASEBOARD_FAB2 (Tioga Pass) — schematic netlist excerpt (pin names and nets, part order shuffled) for the footprints in the layout excerpt that follows; sources: Cadence DE-HDL packaged netlist, KiCad conversion of Wiwynn_Tioga_Pass_MB.brd

R5N4  RES  1.8K 1% CHIP  pkg 0402  page 21 : A = P3V3_STBY ; B = FM_CPU0_PROC_ID0
R7M6  RES  665 1.0% CHIP  pkg 0402  page 99 : A = PVPP_KLM ; B = SMB_DDR_KLM_VPP_SDA_R
R3N22  RES  4.02K 1% CHIP  pkg 0402  page 211 : A = VR_PVCCIO_CPU0_XADDR2 ; B = GND

(kicad_pcb
	(version 20260206)
	(generator "pcbnew")
	(generator_version "10.0")
	(general
		(thickness 1.6)
		(legacy_teardrops no)
	)
	(paper "A4")
	(title_block
		(title "Wiwynn_Tioga_Pass_MB.brd")
		(comment 1 "Tioga Pass / footprints 2555-2557 of 4770")
	)
	(layers
		(0 "F.Cu" signal "TOP")
		(4 "In1.Cu" signal "L2GND")
		(6 "In2.Cu" signal "L3")
		(8 "In3.Cu" signal "L4GND")
		(10 "In4.Cu" signal "L5")
		(12 "In5.Cu" signal "L6GND")
		(14 "In6.Cu" signal "L7VCC")
		(16 "In7.Cu" signal "L8VCC")
		(18 "In8.Cu" signal "L9GND")
		(20 "In9.Cu" signal "L10")
		(22 "In10.Cu" signal "L11GND")
		(24 "In11.Cu" signal "L12")
		(26 "In12.Cu" signal "L13GND")
		(2 "B.Cu" signal "BOTTOM")
		(9 "F.Adhes" user "F.Adhesive")
		(11 "B.Adhes" user "B.Adhesive")
		(13 "F.Paste" user "Package Geometry/Pastemask Top")
		(15 "B.Paste" user "Package Geometry/Pastemask Bottom")
		(5 "F.SilkS" user "Ref Des/Silkscreen Top")
		(7 "B.SilkS" user "Ref Des/Silkscreen Bottom")
		(1 "F.Mask" user "Board Geometry/Soldermask Top")
		(3 "B.Mask" user "Board Geometry/Soldermask Bottom")
		(17 "Dwgs.User" user "User.Drawings")
		(19 "Cmts.User" user "User.Comments")
		(21 "Eco1.User" user "User.Eco1")
		(23 "Eco2.User" user "User.Eco2")
		(25 "Edge.Cuts" user "Board Geometry/Outline")
		(27 "Margin" user)
		(31 "F.CrtYd" user "Package Geometry/Place Bound Top")
		(29 "B.CrtYd" user "Package Geometry/Place Bound Bottom")
		(35 "F.Fab" user "Ref Des/Assembly Top")
		(33 "B.Fab" user "Ref Des/Assembly Bottom")
	)
	(footprint ""
		(layer "B.Cu")
		(at 158.6738 -123.8504)
		(property "Reference" "R7M6"
			(at 0 0 0)
			(layer "B.SilkS")
			(hide yes)
			(effects
				(font
					(size 1.27 1.27)
				)
				(justify mirror)
			)
		)
		(property "Value" ""
			(at 0 0 0)
			(layer "B.Fab")
			(effects
				(font
					(size 1.27 1.27)
				)
				(justify mirror)
			)
		)
		(duplicate_pad_numbers_are_jumpers no)
		(fp_poly
			(pts
				(xy 0.2794 -0.1016) (xy -0.2794 -0.1016) (xy -0.2794 0.9906) (xy 0.2794 0.9906)
			)
			(stroke
				(width 0)
				(type default)
			)
			(fill no)
			(layer "B.CrtYd")
		)
		(fp_line
			(start -0.2794 -0.1016)
			(end 0.2794 -0.1016)
			(stroke
				(width 0.1)
				(type default)
			)
			(layer "B.Fab")
		)
		(fp_line
			(start -0.2794 0.9906)
			(end -0.2794 -0.1016)
			(stroke
				(width 0.1)
				(type default)
			)
			(layer "B.Fab")
		)
		(fp_line
			(start 0.2794 -0.1016)
			(end 0.2794 0.9906)
			(stroke
				(width 0.1)
				(type default)
			)
			(layer "B.Fab")
		)
		(fp_line
			(start 0.2794 0.9906)
			(end -0.2794 0.9906)
			(stroke
				(width 0.1)
				(type default)
			)
			(layer "B.Fab")
		)
		(pad "1" smd rect
			(at 0 0 180)
			(size 0.508 0.508)
			(layers "B.Cu" "B.Mask" "B.Paste")
			(net "PVPP_KLM")
		)
		(pad "2" smd rect
			(at 0 0.889 180)
			(size 0.508 0.508)
			(layers "B.Cu" "B.Mask" "B.Paste")
			(net "SMB_DDR_KLM_VPP_SDA_R")
		)
		(zone
			(layer "B.Cu")
			(hatch none 0.5)
			(connect_pads
				(clearance 0)
			)
			(min_thickness 0.25)
			(keepout
				(tracks allowed)
				(vias not_allowed)
				(pads allowed)
				(copperpour not_allowed)
				(footprints allowed)
			)
			(placement
				(enabled no)
				(sheetname "")
			)
			(fill
				(thermal_gap 0.5)
				(thermal_bridge_width 0.5)
				(island_removal_mode 0)
			)
			(polygon
				(pts
					(xy 158.9278 -123.5964) (xy 158.4198 -123.5964) (xy 158.4198 -123.2154) (xy 158.9278 -123.2154)
				)
			)
		)
		(zone
			(layer "B.Cu")
			(hatch none 0.5)
			(connect_pads
				(clearance 0)
			)
			(min_thickness 0.25)
			(keepout
				(tracks not_allowed)
				(vias allowed)
				(pads allowed)
				(copperpour not_allowed)
				(footprints allowed)
			)
			(placement
				(enabled no)
				(sheetname "")
			)
			(fill
				(thermal_gap 0.5)
				(thermal_bridge_width 0.5)
				(island_removal_mode 0)
			)
			(polygon
				(pts
					(xy 158.9278 -123.2154) (xy 158.4198 -123.2154) (xy 158.4198 -123.5964) (xy 158.9278 -123.5964)
				)
			)
		)
	)
	(footprint ""
		(layer "B.Cu")
		(at 227.584 -91.059 90)
		(property "Reference" "R5N4"
			(at 0 0 90)
			(layer "B.SilkS")
			(hide yes)
			(effects
				(font
					(size 1.27 1.27)
				)
				(justify mirror)
			)
		)
		(property "Value" ""
			(at 0 0 90)
			(layer "B.Fab")
			(effects
				(font
					(size 1.27 1.27)
				)
				(justify mirror)
			)
		)
		(duplicate_pad_numbers_are_jumpers no)
		(fp_poly
			(pts
				(xy 0.2794 -0.1016) (xy -0.2794 -0.1016) (xy -0.2794 0.9906) (xy 0.2794 0.9906)
			)
			(stroke
				(width 0)
				(type default)
			)
			(fill no)
			(layer "B.CrtYd")
		)
		(fp_line
			(start 0.2794 -0.1016)
			(end 0.2794 0.9906)
			(stroke
				(width 0.1)
				(type default)
			)
			(layer "B.Fab")
		)
		(fp_line
			(start -0.2794 -0.1016)
			(end 0.2794 -0.1016)
			(stroke
				(width 0.1)
				(type default)
			)
			(layer "B.Fab")
		)
		(fp_line
			(start 0.2794 0.9906)
			(end -0.2794 0.9906)
			(stroke
				(width 0.1)
				(type default)
			)
			(layer "B.Fab")
		)
		(fp_line
			(start -0.2794 0.9906)
			(end -0.2794 -0.1016)
			(stroke
				(width 0.1)
				(type default)
			)
			(layer "B.Fab")
		)
		(pad "1" smd rect
			(at 0 0 270)
			(size 0.508 0.508)
			(layers "B.Cu" "B.Mask" "B.Paste")
			(net "P3V3_STBY")
		)
		(pad "2" smd rect
			(at 0 0.889 270)
			(size 0.508 0.508)
			(layers "B.Cu" "B.Mask" "B.Paste")
			(net "FM_CPU0_PROC_ID0")
		)
		(zone
			(layer "B.Cu")
			(hatch none 0.5)
			(connect_pads
				(clearance 0)
			)
			(min_thickness 0.25)
			(keepout
				(tracks allowed)
				(vias not_allowed)
				(pads allowed)
				(copperpour not_allowed)
				(footprints allowed)
			)
			(placement
				(enabled no)
				(sheetname "")
			)
			(fill
				(thermal_gap 0.5)
				(thermal_bridge_width 0.5)
				(island_removal_mode 0)
			)
			(polygon
				(pts
					(xy 227.838 -91.313) (xy 227.838 -90.805) (xy 228.219 -90.805) (xy 228.219 -91.313)
				)
			)
		)
		(zone
			(layer "B.Cu")
			(hatch none 0.5)
			(connect_pads
				(clearance 0)
			)
			(min_thickness 0.25)
			(keepout
				(tracks not_allowed)
				(vias allowed)
				(pads allowed)
				(copperpour not_allowed)
				(footprints allowed)
			)
			(placement
				(enabled no)
				(sheetname "")
			)
			(fill
				(thermal_gap 0.5)
				(thermal_bridge_width 0.5)
				(island_removal_mode 0)
			)
			(polygon
				(pts
					(xy 228.219 -91.313) (xy 228.219 -90.805) (xy 227.838 -90.805) (xy 227.838 -91.313)
				)
			)
		)
	)
	(footprint ""
		(layer "B.Cu")
		(at 351.1296 -89.865962 90)
		(property "Reference" "R3N22"
			(at 0 0 90)
			(layer "B.SilkS")
			(hide yes)
			(effects
				(font
					(size 1.27 1.27)
				)
				(justify mirror)
			)
		)
		(property "Value" ""
			(at 0 0 90)
			(layer "B.Fab")
			(effects
				(font
					(size 1.27 1.27)
				)
				(justify mirror)
			)
		)
		(duplicate_pad_numbers_are_jumpers no)
		(fp_poly
			(pts
				(xy 0.2794 -0.1016) (xy -0.2794 -0.1016) (xy -0.2794 0.9906) (xy 0.2794 0.9906)
			)
			(stroke
				(width 0)
				(type default)
			)
			(fill no)
			(layer "B.CrtYd")
		)
		(fp_line
			(start 0.2794 -0.1016)
			(end 0.2794 0.9906)
			(stroke
				(width 0.1)
				(type default)
			)
			(layer "B.Fab")
		)
		(fp_line
			(start -0.2794 -0.1016)
			(end 0.2794 -0.1016)
			(stroke
				(width 0.1)
				(type default)
			)
			(layer "B.Fab")
		)
		(fp_line
			(start 0.2794 0.9906)
			(end -0.2794 0.9906)
			(stroke
				(width 0.1)
				(type default)
			)
			(layer "B.Fab")
		)
		(fp_line
			(start -0.2794 0.9906)
			(end -0.2794 -0.1016)
			(stroke
				(width 0.1)
				(type default)
			)
			(layer "B.Fab")
		)
		(pad "1" smd rect
			(at 0 0 270)
			(size 0.508 0.508)
			(layers "B.Cu" "B.Mask" "B.Paste")
			(net "VR_PVCCIO_CPU0_XADDR2")
		)
		(pad "2" smd rect
			(at 0 0.889 270)
			(size 0.508 0.508)
			(layers "B.Cu" "B.Mask" "B.Paste")
			(net "GND")
		)
		(zone
			(layer "B.Cu")
			(hatch none 0.5)
			(connect_pads
				(clearance 0)
			)
			(min_thickness 0.25)
			(keepout
				(tracks allowed)
				(vias not_allowed)
				(pads allowed)
				(copperpour not_allowed)
				(footprints allowed)
			)
			(placement
				(enabled no)
				(sheetname "")
			)
			(fill
				(thermal_gap 0.5)
				(thermal_bridge_width 0.5)
				(island_removal_mode 0)
			)
			(polygon
				(pts
					(xy 351.3836 -90.119962) (xy 351.3836 -89.611962) (xy 351.7646 -89.611962) (xy 351.7646 -90.119962)
				)
			)
		)
		(zone
			(layer "B.Cu")
			(hatch none 0.5)
			(connect_pads
				(clearance 0)
			)
			(min_thickness 0.25)
			(keepout
				(tracks not_allowed)
				(vias allowed)
				(pads allowed)
				(copperpour not_allowed)
				(footprints allowed)
			)
			(placement
				(enabled no)
				(sheetname "")
			)
			(fill
				(thermal_gap 0.5)
				(thermal_bridge_width 0.5)
				(island_removal_mode 0)
			)
			(polygon
				(pts
					(xy 351.7646 -90.119962) (xy 351.7646 -89.611962) (xy 351.3836 -89.611962) (xy 351.3836 -90.119962)
				)
			)
		)
	)
)
